# Knox BOM_OCP.xlsx — Pre BOM HB (bom)
| Wiwynn |  |  |  |  |  |  |  | Knox Housing BOM |  |  |  |  |  |
| Model: |  | Knox HU-230 |  |  |  |  |  |  |  |  |  |  |  |
| Project Code.: |  |  |  |  |  |  |  |  |  |  | Version:0.1 |  |  |
| Vendor: |  |  |  |  |  |  |  |  |  |  | 2015/06/12 |  |  |
| No | Level | Part Number |  |  |  | Description | Part Name | Picture | Feature Model | Suppier | Material | Finish | Material  (A,P, M, O SC,CA |
|  |  | 1 | 2 | 3 | 4 |  |  |  |  |  |  |  |  |
|  |  | Main housing |  |  |  |  |  |  |  |  |  |  |  |
|  | 1 | 60.64W94.001 |  |  |  | ASSY MAIN HOUSING NEW C L HU230 | KNOX_HOUSING_ASSY |  | 1 | Priver |  |  | A |
|  | 2 |  | 60.64W04.001 |  |  | ASSY TOP COVER HU230 | COVER TRAY ASSY |  | 1 | Priver |  |  | M |
|  | 3 |  |  | 34.64W07.001 |  | CVR TOP COVER HU230 | COVER_TRAY_KNOX1 |  | 1 | Priver | SGCC (T=1.0mm) |  | M |
|  | 3 |  |  |  |  | 26-411-201-5 | 43-412-200 |  | 2 | Fivetech | Hardened carbon steel | PENTON 376C | SC |
|  | 3 |  |  |  |  | SO_D4_L4 |  |  | 10 | Priver |  |  | SO |
|  | 3 |  |  |  |  | TOP_COVER_PIN |  |  | 1 | Priver |  |  | SO |
|  | 2 |  | 60.64W05.001 |  |  | ASSY LOWER CASE HU230 | BASE_ASSEMBLY1-1-2011__DEFAULT |  | 1 | Priver |  |  | A |
|  | 3 |  |  | 30.64W01.001 |  | CAS LOWER CASE HU230 | KNOX_LOW_CASE_DEFAULT |  | 1 | Priver | SGCC (T=1.6mm) |  | M |
|  | 4 |  |  |  |  | SO-M3-L12.18MM-GUIDE |  |  | 2 | Priver |  |  | SO |
|  | 4 |  |  |  |  | SO-M3-L10.78MM |  |  | 6 | Priver |  |  | SO |
|  | 4 |  |  |  |  | SO-D3-L6MM |  |  | 1 | Priver |  |  | SO |
|  | 4 |  |  |  |  | FAN_TRAY_GUIDE_PIN |  |  | 8 | Priver |  |  | SO |
|  | 4 |  |  |  |  | BSO-M3-L7.8 |  |  | 4 | Priver |  |  | SO |
|  | 3 |  |  | 33.64W40.001 |  | HLDR TRAY LEFT SLIDE HU230 | HDD_TRAY_SLIDE_1_6MM_right |  | 2 | Priver | SGCC (T=1.6mm) |  | M |
|  | 3 |  |  | 33.64W06.001 |  | HLDR TRAY SLIDE HU230 | HDD_TRAY_SLIDE_1_6MM_left |  | 2 | Priver | SGCC (T=1.6mm) |  | M |
|  | 3 |  |  | 47.64W15.001 |  | RUB HDD TRAY STOPPER HU230 | HDD_TRAY_STOP_RUBBER |  | 4 | PinGood | RUBBER |  | O |
|  | 3 |  |  | 33.64W07.001 |  | BRKT TRAY HOLDER_LEFT | SLIDE_HDD_TRAY_HOLDER_LEFT |  | 2 | Priver | SGCC (T=1.0mm) |  | M |
|  | 3 |  |  | 33.64W08.001 |  | BRKT TRAY HOLDER RIGHT | SLIDE_HDD_TRAY_HOLDER_RIGHT |  | 2 | Priver | SGCC (T=1.0mm) |  | M |
|  | 3 |  |  | 33.64W41.001 |  | BRKT VERTICAL RETAINER HU230 | knox_vertical_retainer_1 |  | 2 | Priver | SUS 301 1/2H (T=0.6mm) |  | M |
|  | 3 |  |  | 33.64W09.001 |  | HLDR FAN TRAY 2 | FAN_TRAY_BRACKET_2_FANS |  | 2 | Priver | SGCC (T=0.8mm) |  | M |
|  | 3 |  |  | 33.64W10.001 |  | HLDR FAN TRAY 1 | FAN_TRAY_BRACKET |  | 2 | Priver | SGCC (T=0.8mm) |  | M |
|  | 3 |  |  | 34.64W08.001 |  | CVR CABLE ARM HOLDER HU230 | CABLE_ARM_HOLDER |  | 1 | Priver | SGCC (T=1.6mm) |  | M |
|  | 3 |  |  | 33.64W11.001 |  | BRKT SENSOR BLOCK HU230 | SENSOR_BLOCK |  | 1 | Priver | SGCC (T=0.8mm) |  | M |
|  | 3 |  |  | 33.64W12.001 |  | HLDR CABLE ARM 1 HU230 | CABLE_ARM_01 |  | 2 | Priver | SGCC (T=1.6mm) |  | M |
|  | 3 |  |  | 33.64W13.001 |  | ASSY LINK ARM HU230 | LINKING_ARM_ASSY_ASM_2 |  | 1 | Priver | SGCC (T=1.6mm) |  | M |
|  | 4 |  |  |  |  | HLDR CABLE ARM 2 HU230 | CABLE_ARM_02 |  | 1 | Priver | SGCC (T=1.6mm) |  | M |
|  | 4 |  |  |  |  | 27-731-501-5 | 54-47-078 |  | 1 | Fivetech | Hardened carbon steel | PENTON 376C | SC |
|  | 3 |  |  | 33.64W13.101 |  | ASSY LINK ARM HU230 | LINKING_ARM_ASSY_ASM_2 |  | 1 | Priver | SGCC (T=1.6mm) |  | M |
|  | 4 |  |  |  |  | HLDR CABLE ARM 2 HU230 | CABLE_ARM_02 |  | 1 | Priver | SGCC (T=1.6mm) |  | M |
|  | 4 |  |  |  |  | 27-731-501-5 | 54-47-078 |  | 1 | Fivetech | Hardened carbon steel | PENTON 376C | SC |
|  | 3 |  |  | 42.64W17.001 |  | STRAP TIE TA14-2C-VO | TA14-2C |  | 11 | PinGood | NYLON |  | O |
|  | 3 |  |  | 42.64W18.001 |  | STRAP TIE BST-6A-VO |  |  | 1 | PinGood | NYLON |  | O |
|  | 3 |  |  | 34.64W09.001 |  | BOSS CABLE ARM 5-82MM HU230 | 5-82MM |  | 1 | Priver | SUS 304(Φ5) |  | O |
|  | 3 |  |  | 34.64W10.001 |  | BOSS CABLE ARM 5-24MM HU230 | 5-24MM |  | 2 | Priver | SUS 304(Φ5) |  | O |
|  | 3 |  |  | 60.64W31.001 |  | ASSY MYLAR TAG BASE HU230 |  |  | 1 | Texchu | Mylar |  | O |
|  | 4 |  |  |  | 40.64W07.001 | MYLAR TAG BASE HU230 | KNOX_SERVICE_TAG_BASE |  | 1 | Texchu | Mylar (T=0.76mm) |  | O |
|  | 4 |  |  |  | 40.64W10.001 | MYLAR TAG BASE HU230 | KNOX_SERVICE_TAG_BASE-1 |  | 1 | Texchu | Mylar (T=0.5mm) |  | O |
|  | 3 |  |  | 40.64W08.001 |  | MYLAR TAG HU230 | KNOX_SERVICE_TAG |  | 1 | Texchu | Mylar (T=0.5mm) |  | O |
|  | 3 |  |  |  |  | ROLLER_WASHER |  |  | 4 | Priver |  |  |  |
|  | 2 |  |  | 33.64W36.001 |  | BRKT SIDE EAR KNOX | KNOX_SIDE_EAR |  | 2 | Priver | SGCC (T=2mm) |  | M |
|  | 2 |  |  | 86.1AS26.8R0 |  | SCRW PAN M4L8 | SIDE EAR SCREW |  | 4 | Wen Haou | SAE1018 |  | SC |
|  | 3 |  |  | 33.64W42.001 |  | HLDR DECELERTOR HU230 | DECELERATOR_SPRING_UPPER_LEFT |  | 2 | Priver | SGCC (T=1.0mm) |  | M |
|  | 3 |  |  | 33.64W43.001 |  | BRKT DECELERATOR SPRING | DECELERATOR_SPRING_LOWER_ANY |  | 4 | Priver | SUS301 1/2H (T=0.6mm) |  | M |
|  | 3 |  |  | 40.64W13.001 |  | MYLAR PLUS HU230 | KNOX_PLUS_MYLAR |  | 1 | Texchu | Red Mylar (T=0.15mm) |  | O |
|  | 3 |  |  | 40.64W14.001 |  | MYLAR MINUS HU230 | KNOX_MINUS_MYLAR |  | 1 | Texchu | Mylar (T=0.15mm) |  | O |
|  | 2 |  | 60.64W95.001 |  |  | ASSY NEW C L HDD TRAY HU230 | HDD_SUBTRAY_ASSY_WITH_HAR |  | 2 | Priver |  |  | A |
|  | 3 |  |  | 60.64W49.001 |  | ASSY LEFT EJECTOR HU230 |  |  | 1 | Priver |  |  | A |
|  | 4 |  |  |  | 34.64W20.001 | LATCH EJECTOR RELEASE | Ejector_sheet_spring |  | 1 | Priver | SUS301 1/2H (T=0.5mm) |  | M |
|  | 4 |  |  |  | 34.64W18.001 | LATCH EJECTOR LEFT HU230 | ejector_latch_assembly_left_any |  | 1 | Priver | SGCC (T=3.3mm) | Painting PENTON 376C | M |
|  | 5 |  |  |  |  | EJECTOR_PIN |  |  | 1 | Priver |  |  |  |
|  | 4 |  |  |  | 33.64W44.001 | HLDR EJECTOR LEFT HU230 | GEJECTOR_BRACKET_ANY |  | 1 | Priver | SGCC (T=2.5mm) |  | M |
|  | 5 |  |  |  |  | 57-122-149-02 | 57-122-149-02 |  | 1 | Fivetech |  | PENTON 376C | SC |
|  | 5 |  |  |  |  | BSOS-M5-25-Colly |  |  | 1 | Priver |  |  | SO |
|  | 4 |  |  |  | 34.64W21.001 | SPG EJECTOR HU230 | SPRING |  | 1 | HJ spring |  |  | O |
|  | 4 |  |  |  | 86.00T97.26I | SCRW WAFER M4 L2_53 |  |  | 1 | Wen Haou | SAE1018 |  | SC |
|  | 4 |  |  |  | 86.00T98.28C | SCRW WAFER M5 L4_5 |  |  | 1 | Wen Haou | SAE1018 |  | SC |
|  | 4 |  |  |  | 40.64W12.001 | MYLAR EJECTOR HU230 |  |  | 2 | Texchu | Mylar (T=0.15mm) |  | O |
|  | 4 |  |  |  | 47.64W44.001 | SPONGE EJECTOR HU230 |  |  | 1 | Texchu | E4382 (T=3mm) |  | O |
|  | 4 |  |  |  |  | EJECTOR WASHER |  |  | 1 | Priver |  |  | O |
|  | 3 |  |  | 60.64W50.001 |  | ASSY RIGHT EJECTOR HU230 |  |  | 1 | Priver |  |  | A |
|  | 4 |  |  |  | 34.64W20.001 | LATCH EJECTOR RELEASE | Ejector_sheet_spring |  | 1 | Priver |  |  | M |
|  | 4 |  |  |  | 34.64W19.001 | LATCH EJECTOR RIGHT HU230 | ejector_latch_assembly_right_an_asm |  | 1 | Priver | SGCC (T=3.5mm) | Painting PENTON 376C | M |
|  | 5 |  |  |  |  | EJECTOR_PIN |  |  | 1 | Priver |  |  |  |
|  | 4 |  |  |  | 33.64W45.001 | HLDR EJECTOR RIGHT HU230 | EJECTOR_BRACKET_ANY |  | 1 | Priver | SGCC (T=2.5mm) |  | M |
|  | 5 |  |  |  |  | 57-122-149-02 | 57-122-149-02 |  | 1 | Fivetech |  | PENTON 376C | SC |
|  | 5 |  |  |  |  | BSOS-M5-25-Colly |  |  | 1 | Priver |  |  | SO |
|  | 4 |  |  |  | 34.64W22.001 | SPG RIGHT EJECTOR HU230 | SPRING |  | 1 | HJ spring |  |  | O |
|  | 4 |  |  |  | 86.00T97.26I | SCRW WAFER M4 L2_53 |  |  | 1 | Wen Haou | SAE1018 |  | SC |
|  | 4 |  |  |  | 86.00T98.28C | SCRW WAFER M5 L4_5 |  |  | 1 | Wen Haou | SAE1018 |  | SC |
|  | 4 |  |  |  | 40.64W12.001 | MYLAR EJECTOR HU230 |  |  | 2 | Texchu | Mylar (T=0.15mm) |  | O |
|  | 4 |  |  |  | 47.64W44.001 | SPONGE EJECTOR HU230 |  |  | 1 | Texchu | E4382 (T=3mm) |  | O |
|  | 4 |  |  |  |  | EJECTOR WASHER |  |  | 1 | Priver |  |  | O |
|  | 3 |  |  | 33.64W16.001 |  | BRKT HDD TRAY HU230 | KNOX_HDD_TRAY |  | 1 | Priver (DVT:NCT) (TOOLING MODIFICATION) | SGCC (T=1.2mm) |  | M |
|  | 4 |  |  |  |  | SO-M3-L3.7MM |  |  | 11 | Priver |  |  | SO |
|  | 4 |  |  |  |  | SO-M3-L5.26MM-GUIDE |  |  | 2 | Priver |  |  | SO |
|  | 4 |  |  |  |  | SO-M3-L5.68MM |  |  | 2 | Priver |  |  | SO |
|  | 4 |  |  |  |  | SO-M3-L4.28MM |  |  | 2 | Priver |  |  | SO |
|  | 3 |  |  | 33.64W17.001 |  | BRKT HDD PARTITION HU230 | KNOX_HDD_PARTITION |  | 12 | Priver | SUS 301 1/2H (T=0.5mm) |  | M |
|  | 3 |  |  | 33.64W20.001 |  | BRKT LINK BAR 1 HU230 | HDD_TRAY_LINK_BAR_1 |  | 1 | Priver (DVT:NCT) (TOOLING MODIFICATION) | SGCC (T=1.6mm) |  | M |
|  | 3 |  |  | 33.64W21.001 |  | BRKT LINK BAR 2 HU230 | HDD_TRAY_LINK_BAR_2_NEW |  | 1 | Priver | SGCC (T=1.2mm) |  | M |
|  | 3 |  |  | 33.64W22.001 |  | BRKT LINK BAR 3 HU230 | HDD_TRAY_LINK_BAR_3_NEW |  | 1 | Priver | SGCC (T=1.2mm) |  | M |
|  | 3 |  |  | 33.64W23.001 |  | BRKT LINK BAR 4 HU230 | HDD_TRAY_LINK_BAR_3 |  | 1 | Priver | SGCC (T=1.2mm) |  | M |
|  | 3 |  |  | 33.64W46.001 |  | HLDR SEB HOLDER HU230 | seb_holder_asm |  | 1 | Priver | SGCC (T=1.2mm) |  | M |
|  | 3 |  |  | 33.64W28.001 |  | BRKT SEB HOLDER RIGHT HU230 | SEB_HOLDER_BRACKET |  | 1 | Priver | SGCC (T=1.0mm) |  | M |
|  | 3 |  |  | 33.64W29.001 |  | BRKT SEB HOLDER LEFT HU230 | GSEB_HOLDER_BRACKET |  | 1 | Priver | SGCC (T=1.0mm) |  | M |
|  | 3 |  |  | 33.64W27.001 |  | BRKT SEB HOLDER MID HU230 | GSEB_HOLDER_BRACKET |  | 1 | Priver | SGCC (T=1.0mm) |  | M |
|  | 3 |  |  | 33.64W30.001 |  | BRKT LINK ARM HU230 | HDD_TRAY_LINKING_BAR |  | 1 | Priver | SGCC (T=1.2mm) |  | M |
|  |  |  |  |  |  | SO-M4-L3_65MM |  |  | 1 | Priver |  |  | SO |
|  | 3 |  |  | 86.1AS26.8R0 |  | SCRW PAN M4L8 | SIDE EAR SCREW |  | 1 | Wen Haou | SAE1018 |  | SC |
|  | 3 |  |  | 42.64W06.001 |  | HLDR SEB GUIDE RAIL HU230 | CG-10N |  | 4 | PinGood | NYLON 66 |  | O |
|  | 3 |  |  | 47.64W17.001 |  | RUB HDD ISOLATOR HU230 | HDD_ISOLATOR_ |  | 30 | Texchu | E4382 (T=1.6mm) |  | O |
|  | 3 |  |  | 47.64W32.001 |  | RUB HDD STOPPER HU230 |  |  | 30 | Texchu | E4382 (T=1.6mm) |  | O |
|  | 3 |  |  | 47.64W45.001 |  | RUB HDD SIDE ISOLATOR POTENTIAL HU230 |  |  | 15 | Potential |  |  | O |
|  | 4 |  |  |  | 33.64W33.001 | HLDR BEARING HOLDER HU230 | BEARING_HOLDER_FOR_3_BEARING |  | 1 | Priver | SGCC (T=1.2mm) |  | M |
|  | 4 |  |  |  | 33.64W32.001 | BEARING TRAY HU230 | 7804K105_7804K105 |  | 3 | Priver | SUS304 |  | O |
|  | 3 |  |  | 86.5A534.5R0 |  | SCRW FLAT M3 *5 | SCRW FLAT M3*L4 NI |  | 26 | Wen Haou | SAE1018 |  | SC |
|  | 3 |  |  | 40.64W16.001 |  | MYLAR HDD TRAY DPB MYLAR HU230 |  |  | 1 | Texchu | Mylar (T=0.125mm)  (20130307ADD) |  | O |
|  | 3 |  |  | 40.64W05.001 |  | MYLAR HDD TRAY MYLAR 2 HU230 | KNOX_HDD_TRAY_MYLAR_2 |  | 1 | Texchu | Mylar (T=0.125mm) |  | O |
|  | 3 |  |  | 40.64W15.001 |  | MYLAR HDD TRAY PTB MYLAR HU230 | KNOX_HDD_TRAY_MYLAR_2 |  | 1 | Texchu | Mylar (T=0.125mm) |  | O |
|  | 3 |  |  | 40.64W06.001 |  | MYLAR LINK ARM HU230 | LINKING_ARM_MYLAR |  | 1 | Texchu | Mylar (T=0.2mm) |  | O |
|  | 3 |  |  | 60.64W96.001 |  | ASSY HDD COVER 2 HU230 | KNOX_HDD_COVER_ASM |  | 15 | Priver |  |  | A |
|  | 4 |  |  |  | 34.64W27.001 | CVR HDD COVER 1 HU230 | KNOX_HDD_COVER |  | 1 | Priver | SGCC (T=0.8mm) |  | M |
|  | 4 |  |  |  | 34.64W12.001 | SPG HDD HINGE HU230 | KNOX_HDD_HINGE |  | 1 | HJ spring | SUS 304 (D=2mm) |  | O |
|  | 4 |  |  |  | 34.64W13.101 | LATCH HDD COVER 1 HU230 | KNOX_HDD_LATCH |  | 1 | Priver | SUS 301 1/2H (T=0.5mm) | Painting PENTON 376C | M |
|  | 4 |  |  |  | 47.64W18.001 | RUB HDD PRESS ISOLATOR HU230 | HDD_PRESS_ISOLATOR |  | 1 | Texchu | E4382 (T=6mm) |  | O |
|  | 3 |  |  | 60.64W24.001 |  | ASSY BEARING HOLDER HU230 | BEARING_HOLDER_ASSY |  | 6 | Priver |  |  | A |
|  | 4 |  |  |  | 33.64W31.001 | BRKT BEARING HOLDER HU230 | BEARING_HOLDER |  | 1 | Priver | SGCC (T=1.2mm) |  | M |
|  | 5 |  |  |  |  | BEARING HOLDER STANDOFF |  |  | 1 | Priver |  |  |  |
|  | 4 |  |  |  | 33.64W32.001 | BEARING TRAY HU230 | 7804K105_7804K105 |  | 1 | Priver | SUS304 |  | O |
|  | 4 |  |  |  |  | ROLLER_WASHER |  |  | 1 | Priver |  |  |  |
|  | 3 |  |  | 60.64W27.001 |  | ASSY BEARING HOLDER 3 HU230 | BEARING_HOLDER_FOR_3_BEARING_ASSY |  | 2 | Priver |  |  | A |
|  | 4 |  |  |  | 33.64W33.001 | HLDR BEARING HOLDER HU230 | BEARING_HOLDER_FOR_3_BEARING |  | 1 | Priver | SGCC (T=1.2mm) |  | M |
|  | 5 |  |  |  |  | BEARING HOLDER STANDOFF |  |  | 1 | Priver |  |  |  |
|  | 4 |  |  |  | 33.64W32.001 | BEARING TRAY HU230 | 7804K105_7804K105 |  | 3 | Priver | SUS304 |  | O |
|  | 4 |  |  |  |  | ROLLER_WASHER |  |  | 1 | Priver |  |  |  |
|  | 3 |  |  | 60.64W78.001 |  | ASSY NON-TILTING LEFT HU230 | GHDD_TRAY_HINGE_ASM |  | 1 | Priver |  |  | A |
|  | 4 |  |  |  | 33.64W51.001 | BRKT NON-TILTING LEFT | GASM_HINGE_0319 |  | 1 | Priver |  |  | A |
|  | 4 |  |  |  | 33.64W34.001 | HLDR LEFT HINGE SPRING HU230 | GSPRING_HOLDER_LEFT |  | 1 | Priver | SGCC (T=1.0mm) |  | M |
|  | 4 |  |  |  | 34.64W14.001 | SPG HINGE PUSH SPRING HU230 | HINGE_PUSH_SPRING |  | 1 | HJ spring | SUS 304 (D=1.5mm) |  | O |
|  | 4 |  |  |  | 42.64W07.001 | HLDR HINNGE POM HU230 | HINGE_POM |  | 1 | Shinbo | POM |  | P |
|  | 4 |  |  |  | 34.64W16.001 | LATCH HINGE PUSH LEFT HU230 | GHINGE_BRACKET_LEFT_HOOK |  | 1 | Priver | SGCC (T=1.2mm) | Painting PENTON 376C | M |
|  | 5 |  |  |  |  | HINGE_PUSH_BAR_STANDOFF |  |  | 1 | Priver |  |  |  |
|  | 4 |  |  |  | 34.64W15.001 | SPG PUSH HINGE SPRING 6 HU230 | HINGE_PUSH_SPRING_6 |  | 1 | HJ spring | SUS 304 (D=0.8mm) |  | O |
|  | 4 |  |  |  | 86.00T32.544 | SCRW WAFRE M3.0 L4 NYLOK | 92005A215 |  | 1 | Wen Haou | SAE1018 |  | SC |
|  | 3 |  |  | 60.64W79.001 |  | ASSY NON-TILTING RIGHT HU230 | GHDD_TRAY_HINGE_ASM |  | 1 | Priver |  |  | A |
|  | 4 |  |  |  | 33.64W52.001 | BRKT NON-TILTING RIGHT | GASM_HINGE_0319 |  | 1 | Priver |  |  | A |
|  | 4 |  |  |  | 33.64W35.001 | HLDR RIGHT HINGE SPRING HU230 | GSPRING_HOLDER_LEFT |  | 1 | Priver | SGCC (T=1.0mm) |  | M |
|  | 4 |  |  |  | 34.64W14.001 | SPG HINGE PUSH SPRING HU230 | HINGE_PUSH_SPRING |  | 1 | HJ spring | SUS 304 (D=1.5mm) |  | O |
|  | 4 |  |  |  | 42.64W07.001 | HLDR HINNGE POM HU230 | HINGE_POM |  | 1 | Priver | POM |  | P |
|  | 4 |  |  |  | 34.64W17.001 | LATCH HINGE PUSH RIGHT HU230 | GHINGE_BRACKET_LEFT_HOOK |  | 1 | Priver | SGCC (T=1.2mm) | Painting PENTON 376C | M |
|  |  |  |  |  |  | HINGE_PUSH_BAR_STANDOFF |  |  | 1 | Priver |  |  |  |
|  | 4 |  |  |  | 34.64W15.001 | SPG PUSH HINGE SPRING 6 HU230 | HINGE_PUSH_SPRING_6 |  | 1 | HJ spring | SUS 304 (D=0.8mm) |  | O |
|  | 4 |  |  |  | 86.00T32.544 | SCRW WAFRE M3.0 L4 NYLOK | 92005A215 |  | 1 | Wen Haou | SAE1018 |  | SC |
|  |  | Singal ship |  |  |  |  |  |  |  |  |  |  |  |
|  | 1 | 33.64W48.001 |  |  |  | HLDR HOLDER CHOCK HU230 | KNOX_CHOCK_HOLDER |  | 1 | Priver | SUS301 1/2H (T=0.5mm) |  | M |
|  | 1 | 42.64W16.001 |  |  |  | HLDR PTB GUIDER 1 HU230 | PLASTIC RAMP |  | 2 | Shinbo | PC+ABS |  | P |
|  | 1 | 60.64W43.001 |  |  |  | ASSY SEB RIGHT HANDLE HU230 | KNOX_SEB_HANDLE_ASSY |  | 1 | Priver |  | Painting PENTON 376C | M |
|  | 2 |  | 33.64W01.001 |  |  | BRKT SEB RIGHT HU230 | knox_seb_bracket_any |  | 1 | Priver | SGCC (T=1.0mm) |  | M |
|  | 2 |  |  |  |  | 27-111-201-5 | 46-111-215 |  | 1 | Fivetech | HARDENED CARBON STEEL& ALUMINUM | PENTON 376C | SC |
|  | 1 | 60.64W44.001 |  |  |  | ASSY SEB LEFT HANDLE HU230 | KNOX_SEB_HANDLE_ASSY_LEFT |  | 1 | Priver |  | Painting PENTON 376C | M |
|  | 2 |  | 33.64W05.001 |  |  | BRKT SEB LEFT HU230 | gknox_seb_bracket_any |  | 1 | Priver | SGCC (T=1.0mm) |  | M |
|  | 2 |  |  |  |  | 27-111-201-5 | 46-111-215 |  | 1 | Fivetech | HARDENED CARBON STEEL& ALUMINUM | PENTON 376C | SC |
|  | 1 | 42.64W15.001 |  |  |  | HLDR FAN CONN 1 HU230 | FAN_CONN_HOLDER |  | 6 | Shinbo | PC+ABS |  | P |
|  |  | DELTA fan module(Singal ship) |  |  |  |  |  |  |  |  |  |  |  |
|  | 1 | 60.64W07.001 |  |  |  | ASSY FAN TRAY HU230 | FAN_TRAY_ASSY |  | 6 | Priver |  |  | A |
|  | 2 |  | 60.64W20.001 |  |  | ASSY FAN CAGE HU230 | KNOX_FAN_TRAY |  | 1 | Priver |  |  | M |
|  | 3 |  |  | 33.64W14.001 |  | HLDR FAN TRAY HU230 | FAN_TRAY |  | 1 | Priver | SGCC (T=0.8mm) |  | M |
|  | 3 |  |  |  |  | 27-111-201-5 | 13-111-501 |  | 1 | Fivetech |  | PENTON 376C | SC |
|  | 3 |  |  |  |  | FAN_TRAY_GUIDE_PIN_0.8MM |  |  | 2 | Priver |  |  | SO |
|  | 2 |  | 33.64W37.001 |  |  | BRKT FAN LINKING HU230 | FILLET13 |  | 2 | Priver | SGCC (T=0.8mm) |  | M |
|  | 2 |  | 33.64W15.001 |  |  | HLDR FAN HANDLE HU230 | FAN_TRAY_HANDLE |  | 1 | Priver | SGCC (T=0.8mm) |  | M |
|  |  | Sunon fan module(Singal ship) |  |  |  |  |  |  |  |  |  |  |  |
|  | 1 | 60.64W48.001 |  |  |  | ASSY SUNON FAN CAGE HU230 | FAN_TRAY_ASSY |  | 6 | Priver |  |  | A |
|  | 2 |  | 60.64W42.001 |  |  | ASSY SUNON FAN CAGE | KNOX_FAN_TRAY |  | 1 | Priver |  |  | M |
|  | 3 |  |  | 33.64W47.001 |  | HLDR SUNON FAN TRAY HU230 | FAN_TRAY |  | 1 | Priver | SGCC (T=0.8mm) |  | M |
|  | 3 |  |  |  |  | 27-111-201-5 | 13-111-501 |  | 1 | Fivetech |  | PENTON 376C | SC |
|  | 3 |  |  |  |  | FAN_TRAY_GUIDE_PIN_0.8MM |  |  | 2 | Priver |  |  | SO |
|  | 2 |  | 33.64W37.001 |  |  | BRKT FAN LINKING HU230 | FILLET13 |  | 2 | Priver | SGCC (T=0.8mm) |  | M |
|  | 2 |  | 33.64W15.001 |  |  | HLDR FAN HANDLE HU230 | FAN_TRAY_HANDLE |  | 1 | Priver | SGCC (T=0.8mm) |  | M |
|  |  | Fan module accessory(Singal ship) |  |  |  |  |  |  |  |  |  |  |  |
|  | 1 | 31.64W01.001 |  |  |  | PLT FAN CONN STOPPER HU230 | FAN_TRAY_CONNECTOR_STOP |  | 6 | Priver | SGCC (T=0.8mm) |  | M |
|  | 1 | 42.64W14.001 |  |  |  | HLDR FAN CONN HOLDER 1 HU230 | FAN_TRAY_CONN_HOLDER |  | 6 | Shinbo | PC+ABS |  | P |
|  |  | Fan |  |  |  |  |  |  |  |  |  |  |  |
|  | 1 | 60.64W02.001 |  |  |  | ASSY FAN 60X60X56MM 50MM KNOX DELTA | 92005A215 |  | 1 | Delta |  |  | FAN |
|  | 2 | 23.10758.001 |  |  |  | FAN PSD1206 5P50MM SUNON 60X60X60MM KNOX |  |  | 1 | Sunon |  |  | FAN |
|  |  | Cable |  |  |  |  |  |  |  |  |  |  |  |
|  | 1 | 50.64W23.001 |  |  |  | C.A.ALLTOP 2P20S2P L1020 HU230 | 92005A215 |  | 2 | ALL-TOP |  |  | CA |
|  | 1A | 50.64W37.001 |  |  |  | C.A. PWR 2P20S2P L1020 HU230 |  |  | 2 | FCI |  |  | CA |
|  | 2 | 50.64W28.001 |  |  |  | C.A. BUS BAR CLIP 215MM HU230 |  |  | 1 | PORTEN |  |  | CA |
